(kicad_pcb
	(version 20260206)
	(generator "pcbnew")
	(generator_version "10.0")
	(general
		(thickness 1.6)
		(legacy_teardrops no)
	)
	(paper "A4")
	(title_block
		(title "15969-1a.1015WZS0858.brd")
		(comment 1 "Tioga Pass / footprints 19-26 of 295")
	)
	(layers
		(0 "F.Cu" signal "TOP")
		(4 "In1.Cu" signal "L2GND")
		(6 "In2.Cu" signal "L3")
		(8 "In3.Cu" signal "L4")
		(10 "In4.Cu" signal "L5GND")
		(2 "B.Cu" signal "BOTTOM")
		(9 "F.Adhes" user "F.Adhesive")
		(11 "B.Adhes" user "B.Adhesive")
		(13 "F.Paste" user "Package Geometry/Pastemask Top")
		(15 "B.Paste" user "Package Geometry/Pastemask Bottom")
		(5 "F.SilkS" user "Ref Des/Silkscreen Top")
		(7 "B.SilkS" user "Ref Des/Silkscreen Bottom")
		(1 "F.Mask" user "Board Geometry/Soldermask Top")
		(3 "B.Mask" user "Board Geometry/Soldermask Bottom")
		(17 "Dwgs.User" user "User.Drawings")
		(19 "Cmts.User" user "User.Comments")
		(21 "Eco1.User" user "User.Eco1")
		(23 "Eco2.User" user "User.Eco2")
		(25 "Edge.Cuts" user "Board Geometry/Outline")
		(27 "Margin" user)
		(31 "F.CrtYd" user "Package Geometry/Place Bound Top")
		(29 "B.CrtYd" user "Package Geometry/Place Bound Bottom")
		(35 "F.Fab" user "Ref Des/Assembly Top")
		(33 "B.Fab" user "Ref Des/Assembly Bottom")
	)
	(footprint ""
		(layer "F.Cu")
		(at 119.5832 -4.953 90)
		(property "Reference" "R139"
			(at 0 0 90)
			(layer "F.SilkS")
			(hide yes)
			(effects
				(font
					(size 1.27 1.27)
				)
			)
		)
		(property "Value" "10KR2F-2-GP"
			(at 0.064008 -3.993896 90)
			(unlocked yes)
			(layer "F.Fab")
			(hide yes)
			(effects
				(font
					(size 1.016 1.016)
					(thickness 0.1524)
				)
			)
		)
		(property "Device Type" "R402H16"
			(at 0.064008 -5.517896 90)
			(unlocked yes)
			(layer "F.Fab")
			(hide yes)
			(effects
				(font
					(size 1.016 1.016)
					(thickness 0.1524)
				)
			)
		)
		(duplicate_pad_numbers_are_jumpers no)
		(fp_line
			(start 0.508 -0.9398)
			(end -0.508 -0.9398)
			(stroke
				(width 0.1524)
				(type default)
			)
			(layer "F.SilkS")
		)
		(fp_line
			(start -0.508 -0.9398)
			(end -0.508 0.9398)
			(stroke
				(width 0.1524)
				(type default)
			)
			(layer "F.SilkS")
		)
		(fp_rect
			(start -0.508 0.9398)
			(end 0.508 -0.9398)
			(stroke
				(width 0)
				(type default)
			)
			(fill no)
			(layer "F.CrtYd")
		)
		(fp_rect
			(start -0.508 0.9398)
			(end 0.508 -0.9398)
			(stroke
				(width 0)
				(type default)
			)
			(fill no)
			(layer "F.Fab")
		)
		(pad "1" smd custom
			(at 0 -0.4445 90)
			(size 0.1397 0.1397)
			(layers "F.Cu" "F.Mask" "F.Paste")
			(net "P3V3_STBY")
			(options
				(clearance outline)
				(anchor circle)
			)
			(primitives
				(gr_poly
					(pts
						(arc
							(start -0.1778 -0.2794)
							(mid -0.249642 -0.249642)
							(end -0.2794 -0.1778)
						)
						(arc
							(start -0.2794 0.1778)
							(mid -0.249642 0.249642)
							(end -0.1778 0.2794)
						)
						(arc
							(start 0.1778 0.2794)
							(mid 0.249642 0.249642)
							(end 0.2794 0.1778)
						)
						(arc
							(start 0.2794 -0.1778)
							(mid 0.249642 -0.249642)
							(end 0.1778 -0.2794)
						)
					)
					(width 0)
					(fill yes)
				)
			)
		)
		(pad "2" smd custom
			(at 0 0.4445 90)
			(size 0.1397 0.1397)
			(layers "F.Cu" "F.Mask" "F.Paste")
			(net "GPIO_P_IO1_4")
			(options
				(clearance outline)
				(anchor circle)
			)
			(primitives
				(gr_poly
					(pts
						(arc
							(start -0.1778 -0.2794)
							(mid -0.249642 -0.249642)
							(end -0.2794 -0.1778)
						)
						(arc
							(start -0.2794 0.1778)
							(mid -0.249642 0.249642)
							(end -0.1778 0.2794)
						)
						(arc
							(start 0.1778 0.2794)
							(mid 0.249642 0.249642)
							(end 0.2794 0.1778)
						)
						(arc
							(start 0.2794 -0.1778)
							(mid 0.249642 -0.249642)
							(end 0.1778 -0.2794)
						)
					)
					(width 0)
					(fill yes)
				)
			)
		)
	)
	(footprint ""
		(layer "F.Cu")
		(at 15.1638 -32.0548 180)
		(property "Reference" "C30"
			(at 0 0 180)
			(layer "F.SilkS")
			(hide yes)
			(effects
				(font
					(size 1.27 1.27)
				)
			)
		)
		(property "Value" "SCD1U25V3KX-GP"
			(at 0 -2.8194 180)
			(unlocked yes)
			(layer "F.Fab")
			(hide yes)
			(effects
				(font
					(size 1.016 1.016)
					(thickness 0.1524)
				)
			)
		)
		(property "Device Type" "C603H36"
			(at 0 -4.3434 180)
			(unlocked yes)
			(layer "F.Fab")
			(hide yes)
			(effects
				(font
					(size 1.016 1.016)
					(thickness 0.1524)
				)
			)
		)
		(duplicate_pad_numbers_are_jumpers no)
		(fp_line
			(start 0.508 0)
			(end -0.508 0)
			(stroke
				(width 0.2032)
				(type default)
			)
			(layer "F.SilkS")
		)
		(fp_rect
			(start -0.5842 1.3335)
			(end 0.5842 -1.3335)
			(stroke
				(width 0)
				(type default)
			)
			(fill no)
			(layer "F.CrtYd")
		)
		(fp_rect
			(start -0.5842 1.3335)
			(end 0.5842 -1.3335)
			(stroke
				(width 0)
				(type default)
			)
			(fill no)
			(layer "F.Fab")
		)
		(pad "1" smd custom
			(at 0 -0.762 180)
			(size 0.2159 0.2159)
			(layers "F.Cu" "F.Mask" "F.Paste")
			(net "P12V_SLOT3")
			(options
				(clearance outline)
				(anchor circle)
			)
			(primitives
				(gr_poly
					(pts
						(arc
							(start -0.3302 -0.4318)
							(mid -0.402042 -0.402042)
							(end -0.4318 -0.3302)
						)
						(arc
							(start -0.4318 0.3302)
							(mid -0.402042 0.402042)
							(end -0.3302 0.4318)
						)
						(arc
							(start 0.3302 0.4318)
							(mid 0.402042 0.402042)
							(end 0.4318 0.3302)
						)
						(arc
							(start 0.4318 -0.3302)
							(mid 0.402042 -0.402042)
							(end 0.3302 -0.4318)
						)
					)
					(width 0)
					(fill yes)
				)
			)
		)
		(pad "2" smd custom
			(at 0 0.762 180)
			(size 0.2159 0.2159)
			(layers "F.Cu" "F.Mask" "F.Paste")
			(net "GND")
			(options
				(clearance outline)
				(anchor circle)
			)
			(primitives
				(gr_poly
					(pts
						(arc
							(start -0.3302 -0.4318)
							(mid -0.402042 -0.402042)
							(end -0.4318 -0.3302)
						)
						(arc
							(start -0.4318 0.3302)
							(mid -0.402042 0.402042)
							(end -0.3302 0.4318)
						)
						(arc
							(start 0.3302 0.4318)
							(mid 0.402042 0.402042)
							(end 0.4318 0.3302)
						)
						(arc
							(start 0.4318 -0.3302)
							(mid 0.402042 -0.402042)
							(end 0.3302 -0.4318)
						)
					)
					(width 0)
					(fill yes)
				)
			)
		)
	)
	(footprint ""
		(layer "F.Cu")
		(at 21.1836 -31.9532 180)
		(property "Reference" "C92"
			(at 0 0 180)
			(layer "F.SilkS")
			(hide yes)
			(effects
				(font
					(size 1.27 1.27)
				)
			)
		)
		(property "Value" "SC22U16V5MX-4-GP"
			(at -0.0762 -6.1214 180)
			(unlocked yes)
			(layer "F.Fab")
			(hide yes)
			(effects
				(font
					(size 1.016 1.016)
					(thickness 0.1524)
				)
			)
		)
		(property "Device Type" "C805H58"
			(at -0.0762 -8.1534 180)
			(unlocked yes)
			(layer "F.Fab")
			(hide yes)
			(effects
				(font
					(size 1.016 1.016)
					(thickness 0.1524)
				)
			)
		)
		(duplicate_pad_numbers_are_jumpers no)
		(fp_line
			(start 0.635 0)
			(end -0.635 0)
			(stroke
				(width 0.508)
				(type default)
			)
			(layer "F.SilkS")
		)
		(fp_rect
			(start -0.9652 1.778)
			(end 0.9652 -1.778)
			(stroke
				(width 0)
				(type default)
			)
			(fill no)
			(layer "F.CrtYd")
		)
		(fp_poly
			(pts
				(xy -0.9652 -1.778) (xy 0.9652 -1.778) (xy 0.9652 1.778) (xy -0.9652 1.778)
			)
			(stroke
				(width 0)
				(type default)
			)
			(fill no)
			(layer "F.Fab")
		)
		(pad "1" smd rect
			(at 0 -0.9652 180)
			(size 1.397 1.143)
			(layers "F.Cu" "F.Mask" "F.Paste")
			(net "P12V_SLOT3")
		)
		(pad "2" smd rect
			(at 0 0.9652 180)
			(size 1.397 1.143)
			(layers "F.Cu" "F.Mask" "F.Paste")
			(net "GND")
		)
	)
	(footprint ""
		(layer "F.Cu")
		(at 20.467066 -15.75054)
		(property "Reference" "R64"
			(at 0 0 0)
			(layer "F.SilkS")
			(hide yes)
			(effects
				(font
					(size 1.27 1.27)
				)
			)
		)
		(property "Value" "10KR2F-2-GP"
			(at 0.064008 -3.993896 0)
			(unlocked yes)
			(layer "F.Fab")
			(hide yes)
			(effects
				(font
					(size 1.016 1.016)
					(thickness 0.1524)
				)
			)
		)
		(property "Device Type" "R402H16"
			(at 0.064008 -5.517896 0)
			(unlocked yes)
			(layer "F.Fab")
			(hide yes)
			(effects
				(font
					(size 1.016 1.016)
					(thickness 0.1524)
				)
			)
		)
		(duplicate_pad_numbers_are_jumpers no)
		(fp_line
			(start -0.508 -0.9398)
			(end -0.508 0.9398)
			(stroke
				(width 0.1524)
				(type default)
			)
			(layer "F.SilkS")
		)
		(fp_line
			(start 0.508 -0.9398)
			(end -0.508 -0.9398)
			(stroke
				(width 0.1524)
				(type default)
			)
			(layer "F.SilkS")
		)
		(fp_rect
			(start -0.508 0.9398)
			(end 0.508 -0.9398)
			(stroke
				(width 0)
				(type default)
			)
			(fill no)
			(layer "F.CrtYd")
		)
		(fp_rect
			(start -0.508 0.9398)
			(end 0.508 -0.9398)
			(stroke
				(width 0)
				(type default)
			)
			(fill no)
			(layer "F.Fab")
		)
		(pad "1" smd custom
			(at 0 -0.4445)
			(size 0.1397 0.1397)
			(layers "F.Cu" "F.Mask" "F.Paste")
			(net "SLOT2_VMONITOR_A1")
			(options
				(clearance outline)
				(anchor circle)
			)
			(primitives
				(gr_poly
					(pts
						(arc
							(start -0.1778 -0.2794)
							(mid -0.249642 -0.249642)
							(end -0.2794 -0.1778)
						)
						(arc
							(start -0.2794 0.1778)
							(mid -0.249642 0.249642)
							(end -0.1778 0.2794)
						)
						(arc
							(start 0.1778 0.2794)
							(mid 0.249642 0.249642)
							(end 0.2794 0.1778)
						)
						(arc
							(start 0.2794 -0.1778)
							(mid 0.249642 -0.249642)
							(end 0.1778 -0.2794)
						)
					)
					(width 0)
					(fill yes)
				)
			)
		)
		(pad "2" smd custom
			(at 0 0.4445)
			(size 0.1397 0.1397)
			(layers "F.Cu" "F.Mask" "F.Paste")
			(net "GND")
			(options
				(clearance outline)
				(anchor circle)
			)
			(primitives
				(gr_poly
					(pts
						(arc
							(start -0.1778 -0.2794)
							(mid -0.249642 -0.249642)
							(end -0.2794 -0.1778)
						)
						(arc
							(start -0.2794 0.1778)
							(mid -0.249642 0.249642)
							(end -0.1778 0.2794)
						)
						(arc
							(start 0.1778 0.2794)
							(mid 0.249642 0.249642)
							(end 0.2794 0.1778)
						)
						(arc
							(start 0.2794 -0.1778)
							(mid 0.249642 -0.249642)
							(end 0.1778 -0.2794)
						)
					)
					(width 0)
					(fill yes)
				)
			)
		)
	)
	(footprint ""
		(layer "F.Cu")
		(at 131.699 -20.9296 90)
		(property "Reference" "R130"
			(at 0 0 90)
			(layer "F.SilkS")
			(hide yes)
			(effects
				(font
					(size 1.27 1.27)
				)
			)
		)
		(property "Value" "10KR2F-2-GP"
			(at 0.064008 -3.993896 90)
			(unlocked yes)
			(layer "F.Fab")
			(hide yes)
			(effects
				(font
					(size 1.016 1.016)
					(thickness 0.1524)
				)
			)
		)
		(property "Device Type" "R402H16"
			(at 0.064008 -5.517896 90)
			(unlocked yes)
			(layer "F.Fab")
			(hide yes)
			(effects
				(font
					(size 1.016 1.016)
					(thickness 0.1524)
				)
			)
		)
		(duplicate_pad_numbers_are_jumpers no)
		(fp_line
			(start 0.508 -0.9398)
			(end -0.508 -0.9398)
			(stroke
				(width 0.1524)
				(type default)
			)
			(layer "F.SilkS")
		)
		(fp_line
			(start -0.508 -0.9398)
			(end -0.508 0.9398)
			(stroke
				(width 0.1524)
				(type default)
			)
			(layer "F.SilkS")
		)
		(fp_rect
			(start -0.508 0.9398)
			(end 0.508 -0.9398)
			(stroke
				(width 0)
				(type default)
			)
			(fill no)
			(layer "F.CrtYd")
		)
		(fp_rect
			(start -0.508 0.9398)
			(end 0.508 -0.9398)
			(stroke
				(width 0)
				(type default)
			)
			(fill no)
			(layer "F.Fab")
		)
		(pad "1" smd custom
			(at 0 -0.4445 90)
			(size 0.1397 0.1397)
			(layers "F.Cu" "F.Mask" "F.Paste")
			(net "GPIO_B_EXP_A0")
			(options
				(clearance outline)
				(anchor circle)
			)
			(primitives
				(gr_poly
					(pts
						(arc
							(start -0.1778 -0.2794)
							(mid -0.249642 -0.249642)
							(end -0.2794 -0.1778)
						)
						(arc
							(start -0.2794 0.1778)
							(mid -0.249642 0.249642)
							(end -0.1778 0.2794)
						)
						(arc
							(start 0.1778 0.2794)
							(mid 0.249642 0.249642)
							(end 0.2794 0.1778)
						)
						(arc
							(start 0.2794 -0.1778)
							(mid 0.249642 -0.249642)
							(end 0.1778 -0.2794)
						)
					)
					(width 0)
					(fill yes)
				)
			)
		)
		(pad "2" smd custom
			(at 0 0.4445 90)
			(size 0.1397 0.1397)
			(layers "F.Cu" "F.Mask" "F.Paste")
			(net "GND")
			(options
				(clearance outline)
				(anchor circle)
			)
			(primitives
				(gr_poly
					(pts
						(arc
							(start -0.1778 -0.2794)
							(mid -0.249642 -0.249642)
							(end -0.2794 -0.1778)
						)
						(arc
							(start -0.2794 0.1778)
							(mid -0.249642 0.249642)
							(end -0.1778 0.2794)
						)
						(arc
							(start 0.1778 0.2794)
							(mid 0.249642 0.249642)
							(end 0.2794 0.1778)
						)
						(arc
							(start 0.2794 -0.1778)
							(mid 0.249642 -0.249642)
							(end 0.1778 -0.2794)
						)
					)
					(width 0)
					(fill yes)
				)
			)
		)
	)
	(footprint ""
		(layer "F.Cu")
		(at 32.131 3.2512 90)
		(property "Reference" "R203"
			(at 0 0 90)
			(layer "F.SilkS")
			(hide yes)
			(effects
				(font
					(size 1.27 1.27)
				)
			)
		)
		(property "Value" "0R6J-3-GP"
			(at -0.0508 -4.8514 90)
			(unlocked yes)
			(layer "F.Fab")
			(hide yes)
			(effects
				(font
					(size 1.016 1.016)
					(thickness 0.1524)
				)
			)
		)
		(property "Device Type" "R1206H28"
			(at 0 -6.3754 90)
			(unlocked yes)
			(layer "F.Fab")
			(hide yes)
			(effects
				(font
					(size 1.016 1.016)
					(thickness 0.1524)
				)
			)
		)
		(duplicate_pad_numbers_are_jumpers no)
		(fp_line
			(start 1.016 -2.2352)
			(end 1.016 2.2352)
			(stroke
				(width 0.1524)
				(type default)
			)
			(layer "F.SilkS")
		)
		(fp_line
			(start -1.016 -2.2352)
			(end 1.016 -2.2352)
			(stroke
				(width 0.1524)
				(type default)
			)
			(layer "F.SilkS")
		)
		(fp_line
			(start 1.016 2.2352)
			(end -1.016 2.2352)
			(stroke
				(width 0.1524)
				(type default)
			)
			(layer "F.SilkS")
		)
		(fp_line
			(start -1.016 2.2352)
			(end -1.016 -2.2352)
			(stroke
				(width 0.1524)
				(type default)
			)
			(layer "F.SilkS")
		)
		(fp_rect
			(start -1.0922 2.3114)
			(end 1.0922 -2.3114)
			(stroke
				(width 0)
				(type default)
			)
			(fill no)
			(layer "F.CrtYd")
		)
		(fp_poly
			(pts
				(xy -1.0922 -2.3114) (xy 1.0922 -2.3114) (xy 1.0922 2.3114) (xy -1.0922 2.3114)
			)
			(stroke
				(width 0)
				(type default)
			)
			(fill no)
			(layer "F.Fab")
		)
		(pad "1" smd rect
			(at 0 -1.397 90)
			(size 1.651 1.27)
			(layers "F.Cu" "F.Mask" "F.Paste")
			(net "P3V3_MB")
		)
		(pad "2" smd rect
			(at 0 1.397 90)
			(size 1.651 1.27)
			(layers "F.Cu" "F.Mask" "F.Paste")
			(net "P3V3")
		)
	)
	(footprint ""
		(layer "F.Cu")
		(at 131.6736 -19.8882 90)
		(property "Reference" "R133"
			(at 0 0 90)
			(layer "F.SilkS")
			(hide yes)
			(effects
				(font
					(size 1.27 1.27)
				)
			)
		)
		(property "Value" "10KR2F-2-GP"
			(at 0.064008 -3.993896 90)
			(unlocked yes)
			(layer "F.Fab")
			(hide yes)
			(effects
				(font
					(size 1.016 1.016)
					(thickness 0.1524)
				)
			)
		)
		(property "Device Type" "R402H16"
			(at 0.064008 -5.517896 90)
			(unlocked yes)
			(layer "F.Fab")
			(hide yes)
			(effects
				(font
					(size 1.016 1.016)
					(thickness 0.1524)
				)
			)
		)
		(duplicate_pad_numbers_are_jumpers no)
		(fp_line
			(start 0.508 -0.9398)
			(end -0.508 -0.9398)
			(stroke
				(width 0.1524)
				(type default)
			)
			(layer "F.SilkS")
		)
		(fp_line
			(start -0.508 -0.9398)
			(end -0.508 0.9398)
			(stroke
				(width 0.1524)
				(type default)
			)
			(layer "F.SilkS")
		)
		(fp_rect
			(start -0.508 0.9398)
			(end 0.508 -0.9398)
			(stroke
				(width 0)
				(type default)
			)
			(fill no)
			(layer "F.CrtYd")
		)
		(fp_rect
			(start -0.508 0.9398)
			(end 0.508 -0.9398)
			(stroke
				(width 0)
				(type default)
			)
			(fill no)
			(layer "F.Fab")
		)
		(pad "1" smd custom
			(at 0 -0.4445 90)
			(size 0.1397 0.1397)
			(layers "F.Cu" "F.Mask" "F.Paste")
			(net "GPIO_B_IO1_7")
			(options
				(clearance outline)
				(anchor circle)
			)
			(primitives
				(gr_poly
					(pts
						(arc
							(start -0.1778 -0.2794)
							(mid -0.249642 -0.249642)
							(end -0.2794 -0.1778)
						)
						(arc
							(start -0.2794 0.1778)
							(mid -0.249642 0.249642)
							(end -0.1778 0.2794)
						)
						(arc
							(start 0.1778 0.2794)
							(mid 0.249642 0.249642)
							(end 0.2794 0.1778)
						)
						(arc
							(start 0.2794 -0.1778)
							(mid 0.249642 -0.249642)
							(end 0.1778 -0.2794)
						)
					)
					(width 0)
					(fill yes)
				)
			)
		)
		(pad "2" smd custom
			(at 0 0.4445 90)
			(size 0.1397 0.1397)
			(layers "F.Cu" "F.Mask" "F.Paste")
			(net "GND")
			(options
				(clearance outline)
				(anchor circle)
			)
			(primitives
				(gr_poly
					(pts
						(arc
							(start -0.1778 -0.2794)
							(mid -0.249642 -0.249642)
							(end -0.2794 -0.1778)
						)
						(arc
							(start -0.2794 0.1778)
							(mid -0.249642 0.249642)
							(end -0.1778 0.2794)
						)
						(arc
							(start 0.1778 0.2794)
							(mid 0.249642 0.249642)
							(end 0.2794 0.1778)
						)
						(arc
							(start 0.2794 -0.1778)
							(mid 0.249642 -0.249642)
							(end 0.1778 -0.2794)
						)
					)
					(width 0)
					(fill yes)
				)
			)
		)
	)
	(footprint ""
		(layer "F.Cu")
		(at 25.273 -20.9296 90)
		(property "Reference" "R40"
			(at 0 0 90)
			(layer "F.SilkS")
			(hide yes)
			(effects
				(font
					(size 1.27 1.27)
				)
			)
		)
		(property "Value" "0R2F-1-GP"
			(at 0.064008 -3.993896 90)
			(unlocked yes)
			(layer "F.Fab")
			(hide yes)
			(effects
				(font
					(size 1.016 1.016)
					(thickness 0.1524)
				)
			)
		)
		(property "Device Type" "R402H16"
			(at 0.064008 -5.517896 90)
			(unlocked yes)
			(layer "F.Fab")
			(hide yes)
			(effects
				(font
					(size 1.016 1.016)
					(thickness 0.1524)
				)
			)
		)
		(duplicate_pad_numbers_are_jumpers no)
		(fp_line
			(start 0.508 -0.9398)
			(end -0.508 -0.9398)
			(stroke
				(width 0.1524)
				(type default)
			)
			(layer "F.SilkS")
		)
		(fp_line
			(start -0.508 -0.9398)
			(end -0.508 0.9398)
			(stroke
				(width 0.1524)
				(type default)
			)
			(layer "F.SilkS")
		)
		(fp_rect
			(start -0.508 0.9398)
			(end 0.508 -0.9398)
			(stroke
				(width 0)
				(type default)
			)
			(fill no)
			(layer "F.CrtYd")
		)
		(fp_rect
			(start -0.508 0.9398)
			(end 0.508 -0.9398)
			(stroke
				(width 0)
				(type default)
			)
			(fill no)
			(layer "F.Fab")
		)
		(pad "1" smd custom
			(at 0 -0.4445 90)
			(size 0.1397 0.1397)
			(layers "F.Cu" "F.Mask" "F.Paste")
			(net "SMB_VMONITOR_SLOT2_MUX_SCL")
			(options
				(clearance outline)
				(anchor circle)
			)
			(primitives
				(gr_poly
					(pts
						(arc
							(start -0.1778 -0.2794)
							(mid -0.249642 -0.249642)
							(end -0.2794 -0.1778)
						)
						(arc
							(start -0.2794 0.1778)
							(mid -0.249642 0.249642)
							(end -0.1778 0.2794)
						)
						(arc
							(start 0.1778 0.2794)
							(mid 0.249642 0.249642)
							(end 0.2794 0.1778)
						)
						(arc
							(start 0.2794 -0.1778)
							(mid 0.249642 -0.249642)
							(end 0.1778 -0.2794)
						)
					)
					(width 0)
					(fill yes)
				)
			)
		)
		(pad "2" smd custom
			(at 0 0.4445 90)
			(size 0.1397 0.1397)
			(layers "F.Cu" "F.Mask" "F.Paste")
			(net "SMCLK_BMC_DEVICE")
			(options
				(clearance outline)
				(anchor circle)
			)
			(primitives
				(gr_poly
					(pts
						(arc
							(start -0.1778 -0.2794)
							(mid -0.249642 -0.249642)
							(end -0.2794 -0.1778)
						)
						(arc
							(start -0.2794 0.1778)
							(mid -0.249642 0.249642)
							(end -0.1778 0.2794)
						)
						(arc
							(start 0.1778 0.2794)
							(mid 0.249642 0.249642)
							(end 0.2794 0.1778)
						)
						(arc
							(start 0.2794 -0.1778)
							(mid 0.249642 -0.249642)
							(end 0.1778 -0.2794)
						)
					)
					(width 0)
					(fill yes)
				)
			)
		)
	)
)
